(kicad_pcb
	(version 20260206)
	(generator "pcbnew")
	(generator_version "10.0")
	(general
		(thickness 1.6)
		(legacy_teardrops no)
	)
	(paper "A4")
	(title_block
		(title "peb — Lightning_PEB_BRD.brd")
		(comment 1 "Lightning (Wiwynn / Facebook NVMe JBOF) / footprints 2288-2294 of 2563")
	)
	(layers
		(0 "F.Cu" signal "TOP")
		(4 "In1.Cu" signal "L2GND")
		(6 "In2.Cu" signal "L3")
		(8 "In3.Cu" signal "L4VCC")
		(10 "In4.Cu" signal "L5VCC")
		(12 "In5.Cu" signal "L6")
		(14 "In6.Cu" signal "L7GND")
		(2 "B.Cu" signal "BOTTOM")
		(9 "F.Adhes" user "F.Adhesive")
		(11 "B.Adhes" user "B.Adhesive")
		(13 "F.Paste" user "Package Geometry/Pastemask Top")
		(15 "B.Paste" user "Package Geometry/Pastemask Bottom")
		(5 "F.SilkS" user "Ref Des/Silkscreen Top")
		(7 "B.SilkS" user "Ref Des/Silkscreen Bottom")
		(1 "F.Mask" user "Board Geometry/Soldermask Top")
		(3 "B.Mask" user "Board Geometry/Soldermask Bottom")
		(17 "Dwgs.User" user "User.Drawings")
		(19 "Cmts.User" user "User.Comments")
		(21 "Eco1.User" user "User.Eco1")
		(23 "Eco2.User" user "User.Eco2")
		(25 "Edge.Cuts" user "Board Geometry/Outline")
		(27 "Margin" user)
		(31 "F.CrtYd" user "Package Geometry/Place Bound Top")
		(29 "B.CrtYd" user "Package Geometry/Place Bound Bottom")
		(35 "F.Fab" user "Ref Des/Assembly Top")
		(33 "B.Fab" user "Ref Des/Assembly Bottom")
	)
	(footprint ""
		(layer "B.Cu")
		(at 269.150084 -18.3896 90)
		(property "Reference" "R2977"
			(at 0 0 90)
			(layer "B.SilkS")
			(hide yes)
			(effects
				(font
					(size 1.27 1.27)
				)
				(justify mirror)
			)
		)
		(property "Value" "0R2J-2-GP"
			(at -0.064008 -3.993896 90)
			(unlocked yes)
			(layer "B.Fab")
			(hide yes)
			(effects
				(font
					(size 1.016 1.016)
					(thickness 0.1524)
				)
				(justify mirror)
			)
		)
		(property "Device Type" "R402H16"
			(at -0.064008 -5.517896 90)
			(unlocked yes)
			(layer "B.Fab")
			(hide yes)
			(effects
				(font
					(size 1.016 1.016)
					(thickness 0.1524)
				)
				(justify mirror)
			)
		)
		(duplicate_pad_numbers_are_jumpers no)
		(fp_line
			(start 0.508 -0.9398)
			(end 0.508 0.9398)
			(stroke
				(width 0.1524)
				(type default)
			)
			(layer "B.SilkS")
		)
		(fp_line
			(start -0.508 -0.9398)
			(end 0.508 -0.9398)
			(stroke
				(width 0.1524)
				(type default)
			)
			(layer "B.SilkS")
		)
		(fp_rect
			(start 0.508 0.9398)
			(end -0.508 -0.9398)
			(stroke
				(width 0)
				(type default)
			)
			(fill no)
			(layer "B.CrtYd")
		)
		(fp_rect
			(start 0.508 0.9398)
			(end -0.508 -0.9398)
			(stroke
				(width 0)
				(type default)
			)
			(fill no)
			(layer "B.Fab")
		)
		(pad "1" smd custom
			(at 0 -0.4445 270)
			(size 0.1397 0.1397)
			(layers "B.Cu" "B.Mask" "B.Paste")
			(net "USB_P4_DN_BMC")
			(options
				(clearance outline)
				(anchor circle)
			)
			(primitives
				(gr_poly
					(pts
						(arc
							(start -0.1778 0.2794)
							(mid -0.249642 0.249642)
							(end -0.2794 0.1778)
						)
						(arc
							(start -0.2794 -0.1778)
							(mid -0.249642 -0.249642)
							(end -0.1778 -0.2794)
						)
						(arc
							(start 0.1778 -0.2794)
							(mid 0.249642 -0.249642)
							(end 0.2794 -0.1778)
						)
						(arc
							(start 0.2794 0.1778)
							(mid 0.249642 0.249642)
							(end 0.1778 0.2794)
						)
					)
					(width 0)
					(fill yes)
				)
			)
		)
		(pad "2" smd custom
			(at 0 0.4445 270)
			(size 0.1397 0.1397)
			(layers "B.Cu" "B.Mask" "B.Paste")
			(net "8644_USB_DN5")
			(options
				(clearance outline)
				(anchor circle)
			)
			(primitives
				(gr_poly
					(pts
						(arc
							(start -0.1778 0.2794)
							(mid -0.249642 0.249642)
							(end -0.2794 0.1778)
						)
						(arc
							(start -0.2794 -0.1778)
							(mid -0.249642 -0.249642)
							(end -0.1778 -0.2794)
						)
						(arc
							(start 0.1778 -0.2794)
							(mid 0.249642 -0.249642)
							(end 0.2794 -0.1778)
						)
						(arc
							(start 0.2794 0.1778)
							(mid 0.249642 0.249642)
							(end 0.1778 0.2794)
						)
					)
					(width 0)
					(fill yes)
				)
			)
		)
	)
	(footprint ""
		(layer "B.Cu")
		(at 237.617 -57.995058 -90)
		(property "Reference" "C524"
			(at 0 0 90)
			(layer "B.SilkS")
			(hide yes)
			(effects
				(font
					(size 1.27 1.27)
				)
				(justify mirror)
			)
		)
		(property "Value" "SCD1U16V1KX-1-GP"
			(at 2.8321 -1.7399 270)
			(unlocked yes)
			(layer "B.Fab")
			(hide yes)
			(effects
				(font
					(size 1.016 1.016)
					(thickness 0.1524)
				)
				(justify mirror)
			)
		)
		(property "Device Type" "C0201H13"
			(at 2.8321 -3.2639 270)
			(unlocked yes)
			(layer "B.Fab")
			(hide yes)
			(effects
				(font
					(size 1.016 1.016)
					(thickness 0.1524)
				)
				(justify mirror)
			)
		)
		(duplicate_pad_numbers_are_jumpers no)
		(fp_rect
			(start 0.2794 0.6477)
			(end -0.2794 -0.6477)
			(stroke
				(width 0)
				(type default)
			)
			(fill no)
			(layer "B.CrtYd")
		)
		(fp_rect
			(start 0.2794 0.6477)
			(end -0.2794 -0.6477)
			(stroke
				(width 0)
				(type default)
			)
			(fill no)
			(layer "B.Fab")
		)
		(pad "1" smd custom
			(at 0 -0.2794 90)
			(size 0.0762 0.0762)
			(layers "B.Cu" "B.Mask" "B.Paste")
			(net "DUT_AVD_TX")
			(options
				(clearance outline)
				(anchor circle)
			)
			(primitives
				(gr_poly
					(pts
						(arc
							(start 0.1524 0.127)
							(mid 0.137521 0.162921)
							(end 0.1016 0.1778)
						)
						(arc
							(start -0.1016 0.1778)
							(mid -0.137521 0.162921)
							(end -0.1524 0.127)
						)
						(arc
							(start -0.1524 -0.127)
							(mid -0.137521 -0.162921)
							(end -0.1016 -0.1778)
						)
						(arc
							(start 0.1016 -0.1778)
							(mid 0.137521 -0.162921)
							(end 0.1524 -0.127)
						)
					)
					(width 0)
					(fill yes)
				)
			)
		)
		(pad "2" smd custom
			(at 0 0.2794 90)
			(size 0.0762 0.0762)
			(layers "B.Cu" "B.Mask" "B.Paste")
			(net "GND")
			(options
				(clearance outline)
				(anchor circle)
			)
			(primitives
				(gr_poly
					(pts
						(arc
							(start 0.1524 0.127)
							(mid 0.137521 0.162921)
							(end 0.1016 0.1778)
						)
						(arc
							(start -0.1016 0.1778)
							(mid -0.137521 0.162921)
							(end -0.1524 0.127)
						)
						(arc
							(start -0.1524 -0.127)
							(mid -0.137521 -0.162921)
							(end -0.1016 -0.1778)
						)
						(arc
							(start 0.1016 -0.1778)
							(mid 0.137521 -0.162921)
							(end 0.1524 -0.127)
						)
					)
					(width 0)
					(fill yes)
				)
			)
		)
	)
	(footprint ""
		(layer "B.Cu")
		(at 35.306 -129.667 90)
		(property "Reference" "C213"
			(at 0 0 90)
			(layer "B.SilkS")
			(hide yes)
			(effects
				(font
					(size 1.27 1.27)
				)
				(justify mirror)
			)
		)
		(property "Value" "SC1U10V2KX-4-GP"
			(at -1.1811 -2.7051 90)
			(unlocked yes)
			(layer "B.Fab")
			(hide yes)
			(effects
				(font
					(size 1.016 1.016)
					(thickness 0.1524)
				)
				(justify mirror)
			)
		)
		(property "Device Type" "C402H22"
			(at -1.1811 -4.2291 90)
			(unlocked yes)
			(layer "B.Fab")
			(hide yes)
			(effects
				(font
					(size 1.016 1.016)
					(thickness 0.1524)
				)
				(justify mirror)
			)
		)
		(duplicate_pad_numbers_are_jumpers no)
		(fp_rect
			(start 0.4318 0.9525)
			(end -0.4318 -0.9525)
			(stroke
				(width 0)
				(type default)
			)
			(fill no)
			(layer "B.CrtYd")
		)
		(fp_rect
			(start 0.4318 0.9525)
			(end -0.4318 -0.9525)
			(stroke
				(width 0)
				(type default)
			)
			(fill no)
			(layer "B.Fab")
		)
		(pad "1" smd custom
			(at 0 -0.4445 270)
			(size 0.1524 0.1524)
			(layers "B.Cu" "B.Mask" "B.Paste")
			(net "P1V26_STBY")
			(options
				(clearance outline)
				(anchor circle)
			)
			(primitives
				(gr_poly
					(pts
						(arc
							(start 0.3048 0.2032)
							(mid 0.275042 0.275042)
							(end 0.2032 0.3048)
						)
						(arc
							(start -0.2032 0.3048)
							(mid -0.275042 0.275042)
							(end -0.3048 0.2032)
						)
						(arc
							(start -0.3048 -0.2032)
							(mid -0.275042 -0.275042)
							(end -0.2032 -0.3048)
						)
						(arc
							(start 0.2032 -0.3048)
							(mid 0.275042 -0.275042)
							(end 0.3048 -0.2032)
						)
					)
					(width 0)
					(fill yes)
				)
			)
		)
		(pad "2" smd custom
			(at 0 0.4445 270)
			(size 0.1524 0.1524)
			(layers "B.Cu" "B.Mask" "B.Paste")
			(net "GND")
			(options
				(clearance outline)
				(anchor circle)
			)
			(primitives
				(gr_poly
					(pts
						(arc
							(start 0.3048 0.2032)
							(mid 0.275042 0.275042)
							(end 0.2032 0.3048)
						)
						(arc
							(start -0.2032 0.3048)
							(mid -0.275042 0.275042)
							(end -0.3048 0.2032)
						)
						(arc
							(start -0.3048 -0.2032)
							(mid -0.275042 -0.275042)
							(end -0.2032 -0.3048)
						)
						(arc
							(start 0.2032 -0.3048)
							(mid 0.275042 -0.275042)
							(end 0.3048 -0.2032)
						)
					)
					(width 0)
					(fill yes)
				)
			)
		)
	)
	(footprint ""
		(layer "B.Cu")
		(at 150.783544 -33.545272 180)
		(property "Reference" "C228"
			(at 0 0 0)
			(layer "B.SilkS")
			(hide yes)
			(effects
				(font
					(size 1.27 1.27)
				)
				(justify mirror)
			)
		)
		(property "Value" "SCD1U10V2KX-5GP"
			(at -1.1811 -2.7051 180)
			(unlocked yes)
			(layer "B.Fab")
			(hide yes)
			(effects
				(font
					(size 1.016 1.016)
					(thickness 0.1524)
				)
				(justify mirror)
			)
		)
		(property "Device Type" "C402H22"
			(at -1.1811 -4.2291 180)
			(unlocked yes)
			(layer "B.Fab")
			(hide yes)
			(effects
				(font
					(size 1.016 1.016)
					(thickness 0.1524)
				)
				(justify mirror)
			)
		)
		(duplicate_pad_numbers_are_jumpers no)
		(fp_rect
			(start 0.4318 0.9525)
			(end -0.4318 -0.9525)
			(stroke
				(width 0)
				(type default)
			)
			(fill no)
			(layer "B.CrtYd")
		)
		(fp_rect
			(start 0.4318 0.9525)
			(end -0.4318 -0.9525)
			(stroke
				(width 0)
				(type default)
			)
			(fill no)
			(layer "B.Fab")
		)
		(pad "1" smd custom
			(at 0 -0.4445)
			(size 0.1524 0.1524)
			(layers "B.Cu" "B.Mask" "B.Paste")
			(net "GND")
			(options
				(clearance outline)
				(anchor circle)
			)
			(primitives
				(gr_poly
					(pts
						(arc
							(start 0.3048 0.2032)
							(mid 0.275042 0.275042)
							(end 0.2032 0.3048)
						)
						(arc
							(start -0.2032 0.3048)
							(mid -0.275042 0.275042)
							(end -0.3048 0.2032)
						)
						(arc
							(start -0.3048 -0.2032)
							(mid -0.275042 -0.275042)
							(end -0.2032 -0.3048)
						)
						(arc
							(start 0.2032 -0.3048)
							(mid 0.275042 -0.275042)
							(end 0.3048 -0.2032)
						)
					)
					(width 0)
					(fill yes)
				)
			)
		)
		(pad "2" smd custom
			(at 0 0.4445)
			(size 0.1524 0.1524)
			(layers "B.Cu" "B.Mask" "B.Paste")
			(net "P3V3_STBY")
			(options
				(clearance outline)
				(anchor circle)
			)
			(primitives
				(gr_poly
					(pts
						(arc
							(start 0.3048 0.2032)
							(mid 0.275042 0.275042)
							(end 0.2032 0.3048)
						)
						(arc
							(start -0.2032 0.3048)
							(mid -0.275042 0.275042)
							(end -0.3048 0.2032)
						)
						(arc
							(start -0.3048 -0.2032)
							(mid -0.275042 -0.275042)
							(end -0.2032 -0.3048)
						)
						(arc
							(start 0.2032 -0.3048)
							(mid 0.275042 -0.275042)
							(end 0.3048 -0.2032)
						)
					)
					(width 0)
					(fill yes)
				)
			)
		)
	)
	(footprint ""
		(layer "B.Cu")
		(at 56.134 -136.271 180)
		(property "Reference" "R3100"
			(at 0 0 0)
			(layer "B.SilkS")
			(hide yes)
			(effects
				(font
					(size 1.27 1.27)
				)
				(justify mirror)
			)
		)
		(property "Value" "1KR2F-3-GP"
			(at -0.064008 -3.993896 180)
			(unlocked yes)
			(layer "B.Fab")
			(hide yes)
			(effects
				(font
					(size 1.016 1.016)
					(thickness 0.1524)
				)
				(justify mirror)
			)
		)
		(property "Device Type" "R402H16"
			(at -0.064008 -5.517896 180)
			(unlocked yes)
			(layer "B.Fab")
			(hide yes)
			(effects
				(font
					(size 1.016 1.016)
					(thickness 0.1524)
				)
				(justify mirror)
			)
		)
		(duplicate_pad_numbers_are_jumpers no)
		(fp_line
			(start 0.508 -0.9398)
			(end 0.508 0.9398)
			(stroke
				(width 0.1524)
				(type default)
			)
			(layer "B.SilkS")
		)
		(fp_line
			(start -0.508 -0.9398)
			(end 0.508 -0.9398)
			(stroke
				(width 0.1524)
				(type default)
			)
			(layer "B.SilkS")
		)
		(fp_rect
			(start 0.508 0.9398)
			(end -0.508 -0.9398)
			(stroke
				(width 0)
				(type default)
			)
			(fill no)
			(layer "B.CrtYd")
		)
		(fp_rect
			(start 0.508 0.9398)
			(end -0.508 -0.9398)
			(stroke
				(width 0)
				(type default)
			)
			(fill no)
			(layer "B.Fab")
		)
		(pad "1" smd custom
			(at 0 -0.4445)
			(size 0.1397 0.1397)
			(layers "B.Cu" "B.Mask" "B.Paste")
			(net "ADC_P0V9_E")
			(options
				(clearance outline)
				(anchor circle)
			)
			(primitives
				(gr_poly
					(pts
						(arc
							(start -0.1778 0.2794)
							(mid -0.249642 0.249642)
							(end -0.2794 0.1778)
						)
						(arc
							(start -0.2794 -0.1778)
							(mid -0.249642 -0.249642)
							(end -0.1778 -0.2794)
						)
						(arc
							(start 0.1778 -0.2794)
							(mid 0.249642 -0.249642)
							(end 0.2794 -0.1778)
						)
						(arc
							(start 0.2794 0.1778)
							(mid 0.249642 0.249642)
							(end 0.1778 0.2794)
						)
					)
					(width 0)
					(fill yes)
				)
			)
		)
		(pad "2" smd custom
			(at 0 0.4445)
			(size 0.1397 0.1397)
			(layers "B.Cu" "B.Mask" "B.Paste")
			(net "GND")
			(options
				(clearance outline)
				(anchor circle)
			)
			(primitives
				(gr_poly
					(pts
						(arc
							(start -0.1778 0.2794)
							(mid -0.249642 0.249642)
							(end -0.2794 0.1778)
						)
						(arc
							(start -0.2794 -0.1778)
							(mid -0.249642 -0.249642)
							(end -0.1778 -0.2794)
						)
						(arc
							(start 0.1778 -0.2794)
							(mid 0.249642 -0.249642)
							(end 0.2794 -0.1778)
						)
						(arc
							(start 0.2794 0.1778)
							(mid 0.249642 0.249642)
							(end 0.1778 0.2794)
						)
					)
					(width 0)
					(fill yes)
				)
			)
		)
	)
	(footprint ""
		(layer "B.Cu")
		(at 222.541592 -194.284092 -90)
		(property "Reference" "C3203"
			(at 0 0 90)
			(layer "B.SilkS")
			(hide yes)
			(effects
				(font
					(size 1.27 1.27)
				)
				(justify mirror)
			)
		)
		(property "Value" "SCD1U25V2KX-2-GP"
			(at -1.1811 -2.7051 270)
			(unlocked yes)
			(layer "B.Fab")
			(hide yes)
			(effects
				(font
					(size 1.016 1.016)
					(thickness 0.1524)
				)
				(justify mirror)
			)
		)
		(property "Device Type" "C402H22"
			(at -1.1811 -4.2291 270)
			(unlocked yes)
			(layer "B.Fab")
			(hide yes)
			(effects
				(font
					(size 1.016 1.016)
					(thickness 0.1524)
				)
				(justify mirror)
			)
		)
		(duplicate_pad_numbers_are_jumpers no)
		(fp_rect
			(start 0.4318 0.9525)
			(end -0.4318 -0.9525)
			(stroke
				(width 0)
				(type default)
			)
			(fill no)
			(layer "B.CrtYd")
		)
		(fp_rect
			(start 0.4318 0.9525)
			(end -0.4318 -0.9525)
			(stroke
				(width 0)
				(type default)
			)
			(fill no)
			(layer "B.Fab")
		)
		(pad "1" smd custom
			(at 0 -0.4445 90)
			(size 0.1524 0.1524)
			(layers "B.Cu" "B.Mask" "B.Paste")
			(net "P3V3_STBY")
			(options
				(clearance outline)
				(anchor circle)
			)
			(primitives
				(gr_poly
					(pts
						(arc
							(start 0.3048 0.2032)
							(mid 0.275042 0.275042)
							(end 0.2032 0.3048)
						)
						(arc
							(start -0.2032 0.3048)
							(mid -0.275042 0.275042)
							(end -0.3048 0.2032)
						)
						(arc
							(start -0.3048 -0.2032)
							(mid -0.275042 -0.275042)
							(end -0.2032 -0.3048)
						)
						(arc
							(start 0.2032 -0.3048)
							(mid 0.275042 -0.275042)
							(end 0.3048 -0.2032)
						)
					)
					(width 0)
					(fill yes)
				)
			)
		)
		(pad "2" smd custom
			(at 0 0.4445 90)
			(size 0.1524 0.1524)
			(layers "B.Cu" "B.Mask" "B.Paste")
			(net "GND")
			(options
				(clearance outline)
				(anchor circle)
			)
			(primitives
				(gr_poly
					(pts
						(arc
							(start 0.3048 0.2032)
							(mid 0.275042 0.275042)
							(end 0.2032 0.3048)
						)
						(arc
							(start -0.2032 0.3048)
							(mid -0.275042 0.275042)
							(end -0.3048 0.2032)
						)
						(arc
							(start -0.3048 -0.2032)
							(mid -0.275042 -0.275042)
							(end -0.2032 -0.3048)
						)
						(arc
							(start 0.2032 -0.3048)
							(mid 0.275042 -0.275042)
							(end 0.3048 -0.2032)
						)
					)
					(width 0)
					(fill yes)
				)
			)
		)
	)
	(footprint ""
		(layer "B.Cu")
		(at 81.833212 -186.545474)
		(property "Reference" "C3211"
			(at 0 0 0)
			(layer "B.SilkS")
			(hide yes)
			(effects
				(font
					(size 1.27 1.27)
				)
				(justify mirror)
			)
		)
		(property "Value" "SCD1U25V2KX-2-GP"
			(at -1.1811 -2.7051 0)
			(unlocked yes)
			(layer "B.Fab")
			(hide yes)
			(effects
				(font
					(size 1.016 1.016)
					(thickness 0.1524)
				)
				(justify mirror)
			)
		)
		(property "Device Type" "C402H22"
			(at -1.1811 -4.2291 0)
			(unlocked yes)
			(layer "B.Fab")
			(hide yes)
			(effects
				(font
					(size 1.016 1.016)
					(thickness 0.1524)
				)
				(justify mirror)
			)
		)
		(duplicate_pad_numbers_are_jumpers no)
		(fp_rect
			(start 0.4318 0.9525)
			(end -0.4318 -0.9525)
			(stroke
				(width 0)
				(type default)
			)
			(fill no)
			(layer "B.CrtYd")
		)
		(fp_rect
			(start 0.4318 0.9525)
			(end -0.4318 -0.9525)
			(stroke
				(width 0)
				(type default)
			)
			(fill no)
			(layer "B.Fab")
		)
		(pad "1" smd custom
			(at 0 -0.4445 180)
			(size 0.1524 0.1524)
			(layers "B.Cu" "B.Mask" "B.Paste")
			(net "P3V3_STBY")
			(options
				(clearance outline)
				(anchor circle)
			)
			(primitives
				(gr_poly
					(pts
						(arc
							(start 0.3048 0.2032)
							(mid 0.275042 0.275042)
							(end 0.2032 0.3048)
						)
						(arc
							(start -0.2032 0.3048)
							(mid -0.275042 0.275042)
							(end -0.3048 0.2032)
						)
						(arc
							(start -0.3048 -0.2032)
							(mid -0.275042 -0.275042)
							(end -0.2032 -0.3048)
						)
						(arc
							(start 0.2032 -0.3048)
							(mid 0.275042 -0.275042)
							(end 0.3048 -0.2032)
						)
					)
					(width 0)
					(fill yes)
				)
			)
		)
		(pad "2" smd custom
			(at 0 0.4445 180)
			(size 0.1524 0.1524)
			(layers "B.Cu" "B.Mask" "B.Paste")
			(net "GND")
			(options
				(clearance outline)
				(anchor circle)
			)
			(primitives
				(gr_poly
					(pts
						(arc
							(start 0.3048 0.2032)
							(mid 0.275042 0.275042)
							(end 0.2032 0.3048)
						)
						(arc
							(start -0.2032 0.3048)
							(mid -0.275042 0.275042)
							(end -0.3048 0.2032)
						)
						(arc
							(start -0.3048 -0.2032)
							(mid -0.275042 -0.275042)
							(end -0.2032 -0.3048)
						)
						(arc
							(start 0.2032 -0.3048)
							(mid 0.275042 -0.275042)
							(end 0.3048 -0.2032)
						)
					)
					(width 0)
					(fill yes)
				)
			)
		)
	)
)
